FILE_TYPE = CONNECTIVITY;
{Allegro Design Entry HDL 16.6-p007 (v16-6-112F) 10/10/2012}
"PAGE_NUMBER" = 96;
0"NC";
1"PVCCIO_CPU0\g";
2"PVCCIO_CPU1\g";
3"PVDDQ_KLM\g";
4"PVDDQ_GHJ\g";
5"PVDDQ_DEF\g";
6"GND\g";
7"GND\g";
8"PVDDQ_ABC\g";
9"P3V3_STBY\g";
10"P3V3_STBY\g";
11"GND\g";
12"GND\g";
13"GND\g";
14"GND\g";
15"PD_GTL2014_2_VREF";
16"PU_GTL2014_2_DIR";
17"RST_CPU0_LVC3_N";
18"PWRGD_CPU1_LVC3";
19"RST_CPU1_LVC3_N";
20"PWRGD_DRAMPWRGD";
21"PWRGD_DRAMPWRGD";
22"PD_GTL2014_1_VREF";
23"PU_GTL2014_1_DIR";
24"PWRGD_CPU0_LVC3";
25"RST_CPU1_G_N";
26"PWRGD_CPU1_DRAMPWROK_KLM_G";
27"PWRGD_CPU1_DRAMPWROK_GHJ_G";
28"RST_CPU0_G_N";
29"PWRGD_CPU0_DRAMPWROK_ABC_G";
30"PWRGD_CPU0_DRAMPWROK_DEF_G";
31"PWRGD_CPU1_G";
32"PWRGD_CPU0_G";
%"PVCCIO_CPU0"
"1","(1800,4700)","0","mstr_symbols","I1";
;
HDL_POWER"PVCCIO_CPU0"
BODY_TYPE"PLUMBING"
CDS_LIB"mstr_symbols"
VOLTAGE"1.1V";
"G\NAC"1;
%"RES"
"2","(1900,4450)","0","mstr_discrete","I2";
;
CDS_SEC"1"
ROOM"PROC_RSTS_PGOODS"
CDS_LOCATION"R6D12"
SEC"1"
SEC_TYPE"0402"
CDS_LIB"mstr_discrete"
BOM_COST"PROC_SIDEBAND"
WATTAGE"1/16W"
MATERIAL"CHIP"
PACK_TYPE"0402"
TOLERANCE"1%"
VALUE"49.9"
PART_NUMBER"G21796-047"
LOCATION"R6D12";
"A"
$PN"1"1;
"B"
$PN"2"28;
%"PVCCIO_CPU1"
"1","(1800,2425)","0","mstr_symbols","I24";
;
HDL_POWER"PVCCIO_CPU1"
BODY_TYPE"PLUMBING"
CDS_LIB"mstr_symbols"
VOLTAGE"1.1V";
"G\NAC"2;
%"RES"
"2","(1900,2150)","0","mstr_discrete","I25";
;
CDS_SEC"1"
ROOM"PROC_RSTS_PGOODS"
CDS_LOCATION"R3D20"
SEC"1"
SEC_TYPE"0402"
CDS_LIB"mstr_discrete"
BOM_COST"PROC_SIDEBAND"
WATTAGE"1/16W"
MATERIAL"CHIP"
PACK_TYPE"0402"
TOLERANCE"1%"
VALUE"49.9"
PART_NUMBER"G21796-047"
LOCATION"R3D20";
"A"
$PN"1"2;
"B"
$PN"2"25;
%"RES"
"2","(1700,2150)","2","mstr_discrete","I26";
;
CDS_SEC"1"
ROOM"PROC_RSTS_PGOODS"
CDS_LOCATION"R3D15"
SEC"1"
SEC_TYPE"0402"
CDS_LIB"mstr_discrete"
BOM_COST"PROC_SIDEBAND"
WATTAGE"1/16W"
MATERIAL"CHIP"
PACK_TYPE"0402"
TOLERANCE"1%"
VALUE"49.9"
PART_NUMBER"G21796-047"
LOCATION"R3D15";
"A"
$PN"1"2;
"B"
$PN"2"31;
%"PVDDQ_KLM"
"1","(975,2400)","0","mstr_symbols","I27";
;
HDL_POWER"PVDDQ_KLM"
BODY_TYPE"PLUMBING"
CDS_LIB"mstr_symbols"
VOLTAGE"1.2V";
"G\NAC"3;
%"RES"
"2","(975,2150)","0","mstr_discrete","I28";
;
ROOM"PROC_RSTS_PGOODS"
CDS_LOCATION"R7M9"
$SEC"1"
CDS_SEC"1"
CDS_LIB"mstr_discrete"
BOM_COST"PROC_SIDEBAND"
WATTAGE"1/16W"
MATERIAL"CHIP"
PACK_TYPE"0402"
TOLERANCE"1.0%"
VALUE"64.9"
PART_NUMBER"G21796-298"
LOCATION"R7M9";
"A"
$PN"1"3;
"B"
$PN"2"26;
%"PVDDQ_GHJ"
"1","(575,2400)","0","mstr_symbols","I29";
;
HDL_POWER"PVDDQ_GHJ"
BODY_TYPE"PLUMBING"
CDS_LIB"mstr_symbols"
VOLTAGE"1.2V";
"G\NAC"4;
%"RES"
"2","(1700,4450)","2","mstr_discrete","I3";
;
CDS_SEC"1"
ROOM"PROC_RSTS_PGOODS"
CDS_LOCATION"R6D8"
SEC"1"
SEC_TYPE"0402"
CDS_LIB"mstr_discrete"
BOM_COST"PROC_SIDEBAND"
WATTAGE"1/16W"
MATERIAL"CHIP"
PACK_TYPE"0402"
TOLERANCE"1%"
VALUE"49.9"
PART_NUMBER"G21796-047"
LOCATION"R6D8";
"A"
$PN"1"1;
"B"
$PN"2"32;
%"RES"
"2","(575,2150)","0","mstr_discrete","I30";
;
ROOM"PROC_RSTS_PGOODS"
CDS_LOCATION"R3D21"
$SEC"1"
CDS_SEC"1"
CDS_LIB"mstr_discrete"
BOM_COST"PROC_SIDEBAND"
WATTAGE"1/16W"
MATERIAL"CHIP"
PACK_TYPE"0402"
TOLERANCE"1.0%"
VALUE"64.9"
PART_NUMBER"G21796-298"
LOCATION"R3D21";
"A"
$PN"1"4;
"B"
$PN"2"27;
%"RES"
"2","(-2100,4650)","0","mstr_discrete","I36";
;
ROOM"PROC_RSTS_PGOODS"
CDS_LOCATION"R3P36"
$SEC"1"
CDS_SEC"1"
CDS_LIB"mstr_discrete"
BOM_COST"PROC_SIDEBAND"
WATTAGE"1/16W"
MATERIAL"CHIP"
PACK_TYPE"0402"
TOLERANCE"1%"
VALUE"1.00K"
PART_NUMBER"G21796-026"
LOCATION"R3P36";
"A"
$PN"1"10;
"B"
$PN"2"23;
%"PVDDQ_DEF"
"1","(975,4700)","0","mstr_symbols","I4";
;
HDL_POWER"PVDDQ_DEF"
BODY_TYPE"PLUMBING"
CDS_LIB"mstr_symbols"
VOLTAGE"1.2V";
"G\NAC"5;
%"GND"
"1","(-325,3550)","0","mstr_symbols","I41";
;
HDL_POWER"GND"
BODY_TYPE"PLUMBING"
CDS_LIB"mstr_symbols"
SIZE"1B"
VOLTAGE"0.0V";
"A\NAC"6;
%"GTL2014"
"1","(-875,4100)","0","mstr_digital","I42";
;
ROOM"PROC_RSTS_PGOODS"
CDS_LOCATION"U3P1"
$SEC"1"
CDS_SEC"1"
CDS_LIB"mstr_digital"
BOM_COST"PROC_SIDEBAND"
PACK_TYPE"SM"
MATERIAL"IC"
PART_NUMBER"D66151-001"
LOCATION"U3P1";
"A0"
$PN"13"21;
"A1"
$PN"12"21;
"A3"
$PN"9"24;
"A2"
$PN"10"17;
"B2"
$PN"5"28;
"B3"
$PN"6"32;
"B0"
$PN"2"30;
"B1"
$PN"3"29;
"GND<1>"
$PN"8"6;
"GND<2>"
$PN"11"6;
"GND<0>"
$PN"7"6;
"VCC"
$PN"14"10;
"VREF"
$PN"4"22;
"DIR"
$PN"1"23;
%"GND"
"1","(-325,1250)","0","mstr_symbols","I45";
;
HDL_POWER"GND"
BODY_TYPE"PLUMBING"
SIZE"1B"
CDS_LIB"mstr_symbols"
VOLTAGE"0.0V";
"A\NAC"7;
%"GTL2014"
"1","(-875,1800)","0","mstr_digital","I46";
;
ROOM"PROC_RSTS_PGOODS"
CDS_LOCATION"U4C2"
$SEC"1"
CDS_SEC"1"
BOM_COST"PROC_SIDEBAND"
CDS_LIB"mstr_digital"
PACK_TYPE"SM"
MATERIAL"IC"
PART_NUMBER"D66151-001"
LOCATION"U4C2";
"A0"
$PN"13"20;
"A1"
$PN"12"20;
"A3"
$PN"9"18;
"A2"
$PN"10"19;
"B2"
$PN"5"25;
"B3"
$PN"6"31;
"B0"
$PN"2"26;
"B1"
$PN"3"27;
"GND<1>"
$PN"8"7;
"GND<2>"
$PN"11"7;
"GND<0>"
$PN"7"7;
"VCC"
$PN"14"9;
"VREF"
$PN"4"15;
"DIR"
$PN"1"16;
%"RES"
"2","(975,4450)","0","mstr_discrete","I5";
;
ROOM"PROC_RSTS_PGOODS"
CDS_LOCATION"R3P29"
$SEC"1"
CDS_SEC"1"
CDS_LIB"mstr_discrete"
BOM_COST"PROC_SIDEBAND"
WATTAGE"1/16W"
MATERIAL"CHIP"
PACK_TYPE"0402"
TOLERANCE"1.0%"
VALUE"64.9"
PART_NUMBER"G21796-298"
LOCATION"R3P29";
"A"
$PN"1"5;
"B"
$PN"2"30;
%"RES"
"2","(-2100,2350)","0","mstr_discrete","I55";
;
ROOM"PROC_RSTS_PGOODS"
CDS_LOCATION"R4C8"
$SEC"1"
CDS_SEC"1"
CDS_LIB"mstr_discrete"
BOM_COST"PROC_SIDEBAND"
WATTAGE"1/16W"
MATERIAL"CHIP"
PACK_TYPE"0402"
TOLERANCE"1%"
VALUE"1.00K"
PART_NUMBER"G21796-026"
LOCATION"R4C8";
"A"
$PN"1"9;
"B"
$PN"2"16;
%"PVDDQ_ABC"
"1","(575,4700)","0","mstr_symbols","I6";
;
HDL_POWER"PVDDQ_ABC"
BODY_TYPE"PLUMBING"
CDS_LIB"mstr_symbols"
VOLTAGE"1.2V";
"G\NAC"8;
%"P3V3_STBY"
"1","(-2100,2725)","0","mstr_symbols","I65";
;
HDL_POWER"P3V3_STBY"
BODY_TYPE"PLUMBING"
SIZE"1B"
CDS_LIB"mstr_symbols"
VOLTAGE"3.3V";
"G\NAC"9;
%"P3V3_STBY"
"1","(-2100,5050)","0","mstr_symbols","I68";
;
HDL_POWER"P3V3_STBY"
BODY_TYPE"PLUMBING"
CDS_LIB"mstr_symbols"
SIZE"1B"
VOLTAGE"3.3V";
"G\NAC"10;
%"RES"
"1","(-2400,2050)","0","mstr_discrete","I69";
;
CDS_SEC"1"
ROOM"PROC_RSTS_PGOODS"
CDS_LOCATION"R4C9"
SEC"1"
CDS_LIB"mstr_discrete"
SEC_TYPE"0402"
BOM_COST"PROC_SIDEBAND"
WATTAGE"1/16W"
MATERIAL"CHIP"
PACK_TYPE"0402"
TOLERANCE"1%"
VALUE"1.00K"
PART_NUMBER"G21796-026"
LOCATION"R4C9";
"B"
$PN"2"15;
"A"
$PN"1"11;
%"RES"
"2","(575,4450)","0","mstr_discrete","I7";
;
ROOM"PROC_RSTS_PGOODS"
CDS_LOCATION"R3P38"
$SEC"1"
CDS_SEC"1"
CDS_LIB"mstr_discrete"
BOM_COST"PROC_SIDEBAND"
WATTAGE"1/16W"
MATERIAL"CHIP"
PACK_TYPE"0402"
TOLERANCE"1.0%"
VALUE"64.9"
PART_NUMBER"G21796-298"
LOCATION"R3P38";
"A"
$PN"1"8;
"B"
$PN"2"29;
%"GND"
"1","(-2875,1950)","0","mstr_symbols","I70";
;
HDL_POWER"GND"
BODY_TYPE"PLUMBING"
SIZE"1B"
CDS_LIB"mstr_symbols"
VOLTAGE"0.0V";
"A\NAC"11;
%"RES"
"1","(-2400,4350)","0","mstr_discrete","I71";
;
CDS_SEC"1"
ROOM"PROC_RSTS_PGOODS"
CDS_LOCATION"R3P32"
SEC"1"
CDS_LIB"mstr_discrete"
SEC_TYPE"0402"
BOM_COST"PROC_SIDEBAND"
WATTAGE"1/16W"
MATERIAL"CHIP"
PACK_TYPE"0402"
TOLERANCE"1%"
VALUE"1.00K"
PART_NUMBER"G21796-026"
LOCATION"R3P32";
"B"
$PN"2"22;
"A"
$PN"1"12;
%"GND"
"1","(-2775,4225)","0","mstr_symbols","I72";
;
HDL_POWER"GND"
BODY_TYPE"PLUMBING"
CDS_LIB"mstr_symbols"
SIZE"1B"
VOLTAGE"0.0V";
"A\NAC"12;
%"CAP_A"
"1","(-1650,4650)","0","dev_discrete","I73";
;
ROOM"PROC_RSTS_PGOODS"
SEC"1"
SEC_TYPE"0402V"
CDS_SEC"1"
CDS_LIB"dev_discrete"
BOM_COST"PROC_SIDEBAND"
CDS_LOCATION"C3P42"
MATERIAL"X6S"
VOLTAGE"6.3V"
PACK_TYPE"0402V"
TOLERANCE"10%"
VALUE"1.0UF"
PART_NUMBER"D97712-004"
LOCATION"C3P42";
"B"
$PN"2"13;
"A"
$PN"1"10;
%"GND"
"1","(-1650,4450)","0","mstr_symbols","I74";
;
HDL_POWER"GND"
BODY_TYPE"PLUMBING"
SIZE"1B"
CDS_LIB"mstr_symbols"
VOLTAGE"0.0V";
"A\NAC"13;
%"CAP_A"
"1","(-1725,2325)","0","dev_discrete","I75";
;
ROOM"PROC_RSTS_PGOODS"
SEC"1"
SEC_TYPE"0402V"
CDS_SEC"1"
CDS_LIB"dev_discrete"
BOM_COST"PROC_SIDEBAND"
CDS_LOCATION"C4C3"
MATERIAL"X6S"
VOLTAGE"6.3V"
PACK_TYPE"0402V"
TOLERANCE"10%"
VALUE"1.0UF"
PART_NUMBER"D97712-004"
LOCATION"C4C3";
"B"
$PN"2"14;
"A"
$PN"1"9;
%"GND"
"1","(-1725,2125)","0","mstr_symbols","I76";
;
HDL_POWER"GND"
BODY_TYPE"PLUMBING"
SIZE"1B"
CDS_LIB"mstr_symbols"
VOLTAGE"0.0V";
"A\NAC"14;
END.
